# S9S_MB_2U (Grand Teton) — schematic netlist excerpt (pin names and nets, part order shuffled) for the footprints in the layout excerpt that follows; sources: Cadence DE-HDL packaged netlist, KiCad conversion of 03242023_DA0F0TMBIJ0_F0T_Motherboard_J_brd_V01_OCP.brd

J14  SCONN288_ADR50017P087CC  SCONN288_ADR50017-P087CC IO  pkg DDR288S_1-1VXB  page 95
  VIN_BULK0  = P12V_S3_AUX_CPU0_NVDIMM
  RFU0  = TP_CHG_CPU0_DIMM2_FRU_0
  VIN_MGMT  = P3V3_AUX
  HSCL  = I3C_SPD_DDREFGH_CPU0_LVC1_SCL_5
  HSDA  = I3C_SPD_DDREFGH_CPU0_LVC1_SDA
  VSS0  = GND
  DQ0_A  = M_G_CPU0_SA_DQ<0>
  VSS1  = GND
  DQ1_A  = M_G_CPU0_SA_DQ<1>
  VSS2  = GND
  DQS0_A_T  = M_G_CPU0_SA_DQS_DP<0>
  DQS0_A_C  = M_G_CPU0_SA_DQS_DN<0>
  VSS3  = GND
  DQ4_A  = M_G_CPU0_SA_DQ<4>
  VSS4  = GND
  DQ5_A  = M_G_CPU0_SA_DQ<5>
  VSS5  = GND
  DQ8_A  = M_G_CPU0_SA_DQ<8>
  VSS6  = GND
  DQ9_A  = M_G_CPU0_SA_DQ<9>
  VSS7  = GND
  DQS1_A_T  = M_G_CPU0_SA_DQS_DP<1>
  DQS1_A_C  = M_G_CPU0_SA_DQS_DN<1>
  VSS8  = GND
  DQ12_A  = M_G_CPU0_SA_DQ<12>
  VSS9  = GND
  DQ13_A  = M_G_CPU0_SA_DQ<13>
  VSS10  = GND
  DQ16_A  = M_G_CPU0_SA_DQ<16>
  VSS11  = GND
  DQ17_A  = M_G_CPU0_SA_DQ<17>
  VSS12  = GND
  DQS2_A_T  = M_G_CPU0_SA_DQS_DP<2>
  DQS2_A_C  = M_G_CPU0_SA_DQS_DN<2>
  VSS13  = GND
  DQ20_A  = M_G_CPU0_SA_DQ<20>
  VSS14  = GND
  DQ21_A  = M_G_CPU0_SA_DQ<21>
  VSS15  = GND
  DQ24_A  = M_G_CPU0_SA_DQ<24>
  VSS16  = GND
  DQ25_A  = M_G_CPU0_SA_DQ<25>
  VSS17  = GND
  DQS3_A_T  = M_G_CPU0_SA_DQS_DP<3>
  DQS3_A_C  = M_G_CPU0_SA_DQS_DN<3>
  VSS18  = GND
  DQ28_A  = M_G_CPU0_SA_DQ<28>
  VSS19  = GND
  DQ29_A  = M_G_CPU0_SA_DQ<29>
  VSS20  = GND
  CB0_A  = M_G_CPU0_SA_CB<0>
  VSS21  = GND
  CB1_A  = M_G_CPU0_SA_CB<1>
  VSS22  = GND
  DQS4_A_T  = M_G_CPU0_SA_DQS_DP<4>
  DQS4_A_C  = M_G_CPU0_SA_DQS_DN<4>
  VSS23  = GND
  CB4_A  = M_G_CPU0_SA_CB<4>
  VSS24  = GND
  CB5_A  = M_G_CPU0_SA_CB<5>
  VSS25  = GND
  ALERT_N  = M_G_CPU0_ALERT_N
  VSS26  = GND
  CS0_A_N  = M_G_CPU0_SA_CS_N<2>
  VSS27  = GND
  CA0_A  = M_G_CPU0_SA_CA<0>
  VSS28  = GND
  CA2_A  = M_G_CPU0_SA_CA<2>
  VSS29  = GND
  CA4_A  = M_G_CPU0_SA_CA<4>
  VSS30  = GND
  CA6_A  = M_G_CPU0_SA_CA<6>
  VSS31  = GND
  PAR_A  = M_G_CPU0_SA_PAR
  VSS32  = GND
  CA0_B  = M_G_CPU0_SB_CA<0>
  VSS33  = GND
  CA2_B  = M_G_CPU0_SB_CA<2>
  VSS34  = GND
  CA4_B  = M_G_CPU0_SB_CA<4>
  VSS35  = GND
  CA6_B  = M_G_CPU0_SB_CA<6>
  VSS36  = GND
  CS0_B_N  = M_G_CPU0_SB_CS_N<2>
  VSS37  = GND
  \lbd||rsp_a_n\  = M_G_CPU0_SA_RSP<1>
  \lbs||rsp_b_n\  = M_G_CPU0_SB_RSP<1>
  VSS38  = GND
  CB4_B  = M_G_CPU0_SB_CB<4>
  VSS39  = GND
  CB5_B  = M_G_CPU0_SB_CB<5>
  VSS40  = GND
  \dqs9_b_t||tdqs9_b_t||dbi4_b_n\  = M_G_CPU0_SB_DQS_DP<9>
  \dqs9_b_c||tdqs9_b_c\  = M_G_CPU0_SB_DQS_DN<9>
  VSS41  = GND
  CB0_B  = M_G_CPU0_SB_CB<0>
  VSS42  = GND
  CB1_B  = M_G_CPU0_SB_CB<1>
  VSS43  = GND
  DQ0_B  = M_G_CPU0_SB_DQ<0>
  VSS44  = GND
  DQ1_B  = M_G_CPU0_SB_DQ<1>
  VSS45  = GND
  DQS0_B_T  = M_G_CPU0_SB_DQS_DP<0>
  DQS0_B_C  = M_G_CPU0_SB_DQS_DN<0>
  VSS46  = GND
  DQ4_B  = M_G_CPU0_SB_DQ<4>
  VSS47  = GND
  DQ5_B  = M_G_CPU0_SB_DQ<5>
  VSS48  = GND
  DQ8_B  = M_G_CPU0_SB_DQ<8>
  VSS49  = GND
  DQ9_B  = M_G_CPU0_SB_DQ<9>
  VSS50  = GND
  DQS1_B_T  = M_G_CPU0_SB_DQS_DP<1>
  DQS1_B_C  = M_G_CPU0_SB_DQS_DN<1>
  VSS51  = GND
  DQ12_B  = M_G_CPU0_SB_DQ<12>
  VSS52  = GND
  DQ13_B  = M_G_CPU0_SB_DQ<13>
  VSS53  = GND
  DQ16_B  = M_G_CPU0_SB_DQ<16>
  VSS54  = GND
  DQ17_B  = M_G_CPU0_SB_DQ<17>
  VSS55  = GND
  DQS2_B_T  = M_G_CPU0_SB_DQS_DP<2>
  DQS2_B_C  = M_G_CPU0_SB_DQS_DN<2>
  VSS56  = GND
  DQ20_B  = M_G_CPU0_SB_DQ<20>
  VSS57  = GND
  DQ21_B  = M_G_CPU0_SB_DQ<21>
  VSS58  = GND
  DQ24_B  = M_G_CPU0_SB_DQ<24>
  VSS59  = GND
  DQ25_B  = M_G_CPU0_SB_DQ<25>
  VSS60  = GND
  DQS3_B_T  = M_G_CPU0_SB_DQS_DP<3>
  DQS3_B_C  = M_G_CPU0_SB_DQS_DN<3>
  VSS61  = GND
  DQ28_B  = M_G_CPU0_SB_DQ<28>
  VSS62  = GND
  DQ29_B  = M_G_CPU0_SB_DQ<29>
  VSS63  = GND
  RFU1  = TP_CHG_CPU0_DIMM2_FRU_1
  VIN_BULK1  = P12V_S3_AUX_CPU0_NVDIMM
  VIN_BULK2  = P12V_S3_AUX_CPU0_NVDIMM
  \pwr_good||fail_n\  = PWRGD_CHG_CPU0_DIMM2
  HSA  = PD_CHG_CPU0_DIMM2_SAA
  RFU2  = TP_CHG_CPU0_DIMM2_FRU_2
  RFU3  = TP_CHG_CPU0_DIMM2_FRU_3
  VSS64  = GND
  DQ2_A  = M_G_CPU0_SA_DQ<2>
  VSS65  = GND
  DQ3_A  = M_G_CPU0_SA_DQ<3>
  VSS66  = GND
  \dqs5_a_c||tdqs5_a_c||dqs5_a_t||tdqs5_a_t\  = M_G_CPU0_SA_DQS_DN<5>
  \dqs5_a_t||tdqs5_a_t\  = M_G_CPU0_SA_DQS_DP<5>
  VSS67  = GND
  DQ6_A  = M_G_CPU0_SA_DQ<6>
  VSS68  = GND
  DQ7_A  = M_G_CPU0_SA_DQ<7>
  VSS69  = GND
  DQ10_A  = M_G_CPU0_SA_DQ<10>
  VSS70  = GND
  DQ11_A  = M_G_CPU0_SA_DQ<11>
  VSS71  = GND
  \dqs6_a_c||tdqs6_a_c||dqs6_a_t||tdqs6_a_t\  = M_G_CPU0_SA_DQS_DN<6>
  \dqs6_a_t||tdqs6_a_t\  = M_G_CPU0_SA_DQS_DP<6>
  VSS72  = GND
  DQ14_A  = M_G_CPU0_SA_DQ<14>
  VSS73  = GND
  DQ15_A  = M_G_CPU0_SA_DQ<15>
  VSS74  = GND
  DQ18_A  = M_G_CPU0_SA_DQ<18>
  VSS75  = GND
  DQ19_A  = M_G_CPU0_SA_DQ<19>
  VSS76  = GND
  \dqs7_a_c||tdqs7_a_c\  = M_G_CPU0_SA_DQS_DN<7>
  \dqs7_a_t||tdqs7_a_t\  = M_G_CPU0_SA_DQS_DP<7>
  VSS77  = GND
  DQ22_A  = M_G_CPU0_SA_DQ<22>
  VSS78  = GND
  DQ23_A  = M_G_CPU0_SA_DQ<23>
  VSS79  = GND
  DQ26_A  = M_G_CPU0_SA_DQ<26>
  VSS80  = GND
  DQ27_A  = M_G_CPU0_SA_DQ<27>
  VSS81  = GND
  \dqs8_a_c||tdqs8_a_c\  = M_G_CPU0_SA_DQS_DN<8>
  \dqs8_a_t||tdqs8_a_t\  = M_G_CPU0_SA_DQS_DP<8>
  VSS82  = GND
  DQ30_A  = M_G_CPU0_SA_DQ<30>
  VSS83  = GND
  DQ31_A  = M_G_CPU0_SA_DQ<31>
  VSS84  = GND
  CB2_A  = M_G_CPU0_SA_CB<2>
  VSS85  = GND
  CB3_A  = M_G_CPU0_SA_CB<3>
  VSS86  = GND
  \dqs9_a_c||tdqs9_a_c\  = M_G_CPU0_SA_DQS_DN<9>
  \dqs9_a_t||tdqs9_a_t\  = M_G_CPU0_SA_DQS_DP<9>
  VSS87  = GND
  CB6_A  = M_G_CPU0_SA_CB<6>
  VSS88  = GND
  CB7_A  = M_G_CPU0_SA_CB<7>
  VSS89  = GND
  RESET_N  = RST_M_GH_CPU0_FPGA_N
  VSS90  = GND
  CS1_A_N  = M_G_CPU0_SA_CS_N<3>
  VSS91  = GND
  CA1_A  = M_G_CPU0_SA_CA<1>
  VSS92  = GND
  CA3_A  = M_G_CPU0_SA_CA<3>
  VSS93  = GND
  CA5_A  = M_G_CPU0_SA_CA<5>
  VSS94  = GND
  CK_T  = M_G_CPU0_CLK_DP<1>
  CK_C  = M_G_CPU0_CLK_DN<1>
  VSS95  = GND
  RFU4  = TP_CHG_CPU0_DIMM2_FRU_4
  CA1_B  = M_G_CPU0_SB_CA<1>
  VSS96  = GND
  CA3_B  = M_G_CPU0_SB_CA<3>
  VSS97  = GND
  CA5_B  = M_G_CPU0_SB_CA<5>
  VSS98  = GND
  PAR_B  = M_G_CPU0_SB_PAR
  VSS99  = GND
  CS1_B_N  = M_G_CPU0_SB_CS_N<3>
  VSS100  = GND
  RFU5  = TP_CHG_CPU0_DIMM2_FRU_5
  RFU6  = TP_CHG_CPU0_DIMM2_FRU_6
  VSS101  = GND
  CB6_B  = M_G_CPU0_SB_CB<6>
  VSS102  = GND
  CB7_B  = M_G_CPU0_SB_CB<7>
  VSS103  = GND
  DQS4_B_C  = M_G_CPU0_SB_DQS_DN<4>
  DQS4_B_T  = M_G_CPU0_SB_DQS_DP<4>
  VSS104  = GND
  CB2_B  = M_G_CPU0_SB_CB<2>
  VSS105  = GND
  CB3_B  = M_G_CPU0_SB_CB<3>
  VSS106  = GND
  DQ2_B  = M_G_CPU0_SB_DQ<2>
  VSS107  = GND
  DQ3_B  = M_G_CPU0_SB_DQ<3>
  VSS108  = GND
  \dqs5_b_c||tdqs5_b_c\  = M_G_CPU0_SB_DQS_DN<5>
  \dqs5_b_t||tdqs5_b_t\  = M_G_CPU0_SB_DQS_DP<5>
  VSS109  = GND
  DQ6_B  = M_G_CPU0_SB_DQ<6>
  VSS110  = GND
  DQ7_B  = M_G_CPU0_SB_DQ<7>
  VSS111  = GND
  DQ10_B  = M_G_CPU0_SB_DQ<10>
  VSS112  = GND
  DQ11_B  = M_G_CPU0_SB_DQ<11>
  VSS113  = GND
  \dqs6_b_c||tdqs6_b_c\  = M_G_CPU0_SB_DQS_DN<6>
  \dqs6_b_t||tdqs6_b_t\  = M_G_CPU0_SB_DQS_DP<6>
  VSS114  = GND
  DQ14_B  = M_G_CPU0_SB_DQ<14>
  VSS115  = GND
  DQ15_B  = M_G_CPU0_SB_DQ<15>
  VSS116  = GND
  DQ18_B  = M_G_CPU0_SB_DQ<18>
  VSS117  = GND
  DQ19_B  = M_G_CPU0_SB_DQ<19>
  VSS118  = GND
  \dqs7_b_c||tdqs7_b_c\  = M_G_CPU0_SB_DQS_DN<7>
  \dqs7_b_t||tdqs7_b_t\  = M_G_CPU0_SB_DQS_DP<7>
  VSS119  = GND
  DQ22_B  = M_G_CPU0_SB_DQ<22>
  VSS120  = GND
  DQ23_B  = M_G_CPU0_SB_DQ<23>
  VSS121  = GND
  DQ26_B  = M_G_CPU0_SB_DQ<26>
  VSS122  = GND
  DQ27_B  = M_G_CPU0_SB_DQ<27>
  VSS123  = GND
  \dqs8_b_c||tdqs8_b_c\  = M_G_CPU0_SB_DQS_DN<8>
  \dqs8_b_t||tdqs8_b_t\  = M_G_CPU0_SB_DQS_DP<8>
  VSS124  = GND
  DQ30_B  = M_G_CPU0_SB_DQ<30>
  VSS125  = GND
  DQ31_B  = M_G_CPU0_SB_DQ<31>
  VSS126  = GND
  G1  = GND
  G2  = GND
  G3  = GND

(kicad_pcb
	(version 20260206)
	(generator "pcbnew")
	(generator_version "10.0")
	(general
		(thickness 1.6)
		(legacy_teardrops no)
	)
	(paper "A4")
	(title_block
		(title "03242023_DA0F0TMBIJ0_F0T_Motherboard_J_brd_V01_OCP.brd")
		(comment 1 "Grand Teton / footprint 3833 of 6105 (J14), pads 275-291 of 291")
	)
	(layers
		(0 "F.Cu" signal "TOP")
		(4 "In1.Cu" signal "GND")
		(6 "In2.Cu" signal "IN1")
		(8 "In3.Cu" signal "GND1")
		(10 "In4.Cu" signal "IN2")
		(12 "In5.Cu" signal "GND2")
		(14 "In6.Cu" signal "IN3")
		(16 "In7.Cu" signal "GND3")
		(18 "In8.Cu" signal "VCC")
		(20 "In9.Cu" signal "VCC1")
		(22 "In10.Cu" signal "GND4")
		(24 "In11.Cu" signal "IN4")
		(26 "In12.Cu" signal "GND5")
		(28 "In13.Cu" signal "IN5")
		(30 "In14.Cu" signal "GND6")
		(32 "In15.Cu" signal "IN6")
		(34 "In16.Cu" signal "GND7")
		(2 "B.Cu" signal "BOTTOM")
		(9 "F.Adhes" user "F.Adhesive")
		(11 "B.Adhes" user "B.Adhesive")
		(13 "F.Paste" user "Package Geometry/Pastemask Top")
		(15 "B.Paste" user "Package Geometry/Pastemask Bottom")
		(5 "F.SilkS" user "Ref Des/Silkscreen Top")
		(7 "B.SilkS" user "Ref Des/Silkscreen Bottom")
		(1 "F.Mask" user "Board Geometry/Soldermask Top")
		(3 "B.Mask" user "Board Geometry/Soldermask Bottom")
		(17 "Dwgs.User" user "User.Drawings")
		(19 "Cmts.User" user "User.Comments")
		(21 "Eco1.User" user "User.Eco1")
		(23 "Eco2.User" user "User.Eco2")
		(25 "Edge.Cuts" user "Board Geometry/Outline")
		(27 "Margin" user)
		(31 "F.CrtYd" user "Package Geometry/Place Bound Top")
		(29 "B.CrtYd" user "Package Geometry/Place Bound Bottom")
		(35 "F.Fab" user "Ref Des/Assembly Top")
		(33 "B.Fab" user "Ref Des/Assembly Bottom")
	)
	(footprint ""
		(layer "F.Cu")
		(at 438.978548 -258.091686)
		(property "Reference" "J14"
			(at -3.683 -81.702148 0)
			(unlocked yes)
			(layer "F.SilkS")
			(effects
				(font
					(size 0.7874 0.5842)
					(thickness 0.1524)
				)
				(justify left)
			)
		)
		(property "Value" ""
			(at 0 0 0)
			(layer "F.Fab")
			(effects
				(font
					(size 1.27 1.27)
				)
			)
		)
		(duplicate_pad_numbers_are_jumpers no)
		(pad "275" smd rect
			(at 2.050034 52.274978 270)
			(size 0.519938 1.4986)
			(layers "F.Cu" "F.Mask" "F.Paste")
			(net "GND")
		)
		(pad "276" smd rect
			(at 2.050034 53.125116 270)
			(size 0.519938 1.4986)
			(layers "F.Cu" "F.Mask" "F.Paste")
			(net "M_G_CPU0_SB_DQ<23>")
		)
		(pad "277" smd rect
			(at 2.050034 53.975 270)
			(size 0.519938 1.4986)
			(layers "F.Cu" "F.Mask" "F.Paste")
			(net "GND")
		)
		(pad "278" smd rect
			(at 2.050034 54.824884 270)
			(size 0.519938 1.4986)
			(layers "F.Cu" "F.Mask" "F.Paste")
			(net "M_G_CPU0_SB_DQ<26>")
		)
		(pad "279" smd rect
			(at 2.050034 55.675022 270)
			(size 0.519938 1.4986)
			(layers "F.Cu" "F.Mask" "F.Paste")
			(net "GND")
		)
		(pad "280" smd rect
			(at 2.050034 56.524906 270)
			(size 0.519938 1.4986)
			(layers "F.Cu" "F.Mask" "F.Paste")
			(net "M_G_CPU0_SB_DQ<27>")
		)
		(pad "281" smd rect
			(at 2.050034 57.375044 270)
			(size 0.519938 1.4986)
			(layers "F.Cu" "F.Mask" "F.Paste")
			(net "GND")
		)
		(pad "282" smd rect
			(at 2.050034 58.224928 270)
			(size 0.519938 1.4986)
			(layers "F.Cu" "F.Mask" "F.Paste")
			(net "M_G_CPU0_SB_DQS_DN<8>")
		)
		(pad "283" smd rect
			(at 2.050034 59.075066 270)
			(size 0.519938 1.4986)
			(layers "F.Cu" "F.Mask" "F.Paste")
			(net "M_G_CPU0_SB_DQS_DP<8>")
		)
		(pad "284" smd rect
			(at 2.050034 59.92495 270)
			(size 0.519938 1.4986)
			(layers "F.Cu" "F.Mask" "F.Paste")
			(net "GND")
		)
		(pad "285" smd rect
			(at 2.050034 60.775088 270)
			(size 0.519938 1.4986)
			(layers "F.Cu" "F.Mask" "F.Paste")
			(net "M_G_CPU0_SB_DQ<30>")
		)
		(pad "286" smd rect
			(at 2.050034 61.624972 270)
			(size 0.519938 1.4986)
			(layers "F.Cu" "F.Mask" "F.Paste")
			(net "GND")
		)
		(pad "287" smd rect
			(at 2.050034 62.47511 270)
			(size 0.519938 1.4986)
			(layers "F.Cu" "F.Mask" "F.Paste")
			(net "M_G_CPU0_SB_DQ<31>")
		)
		(pad "288" smd rect
			(at 2.050034 63.324994 270)
			(size 0.519938 1.4986)
			(layers "F.Cu" "F.Mask" "F.Paste")
			(net "GND")
		)
		(pad "G1" thru_hole oval
			(at 0 -68.97497)
			(size 2.8194 1.5748)
			(drill oval 2.4384 1.1938)
			(layers "*.Cu" "*.Mask")
			(remove_unused_layers no)
			(net "GND")
			(clearance 0.127)
			(thermal_gap 0.127)
		)
		(pad "G2" thru_hole oval
			(at 0 3.875024)
			(size 2.8194 1.5748)
			(drill oval 2.4384 1.1938)
			(layers "*.Cu" "*.Mask")
			(remove_unused_layers no)
			(net "GND")
			(clearance 0.127)
			(thermal_gap 0.127)
		)
		(pad "G3" thru_hole oval
			(at 0 68.97497)
			(size 2.8194 1.5748)
			(drill oval 2.4384 1.1938)
			(layers "*.Cu" "*.Mask")
			(remove_unused_layers no)
			(net "GND")
			(clearance 0.127)
			(thermal_gap 0.127)
		)
	)
)
